(kicad_pcb
	(version 20260206)
	(generator "pcbnew")
	(generator_version "10.0")
	(general
		(thickness 1.6)
		(legacy_teardrops no)
	)
	(paper "A4")
	(title_block
		(title "Bryce Canyon_SCC_16316-1_OCP.brd")
		(comment 1 "Bryce Canyon / footprints 555-561 of 1561")
	)
	(layers
		(0 "F.Cu" signal "TOP")
		(4 "In1.Cu" signal "L2GND")
		(6 "In2.Cu" signal "L3")
		(8 "In3.Cu" signal "L4VCC")
		(10 "In4.Cu" signal "L5VCC")
		(12 "In5.Cu" signal "L6")
		(14 "In6.Cu" signal "L7GND")
		(2 "B.Cu" signal "BOTTOM")
		(9 "F.Adhes" user "F.Adhesive")
		(11 "B.Adhes" user "B.Adhesive")
		(13 "F.Paste" user "Package Geometry/Pastemask Top")
		(15 "B.Paste" user "Package Geometry/Pastemask Bottom")
		(5 "F.SilkS" user "Ref Des/Silkscreen Top")
		(7 "B.SilkS" user "Ref Des/Silkscreen Bottom")
		(1 "F.Mask" user "Board Geometry/Soldermask Top")
		(3 "B.Mask" user "Board Geometry/Soldermask Bottom")
		(17 "Dwgs.User" user "User.Drawings")
		(19 "Cmts.User" user "User.Comments")
		(21 "Eco1.User" user "User.Eco1")
		(23 "Eco2.User" user "User.Eco2")
		(25 "Edge.Cuts" user "Board Geometry/Outline")
		(27 "Margin" user)
		(31 "F.CrtYd" user "Package Geometry/Place Bound Top")
		(29 "B.CrtYd" user "Package Geometry/Place Bound Bottom")
		(35 "F.Fab" user "Ref Des/Assembly Top")
		(33 "B.Fab" user "Ref Des/Assembly Bottom")
	)
	(footprint ""
		(layer "F.Cu")
		(at 142.99311 -57.7215 -90)
		(property "Reference" "C39"
			(at 0 0 270)
			(layer "F.SilkS")
			(hide yes)
			(effects
				(font
					(size 1.27 1.27)
				)
			)
		)
		(property "Value" "SCD01U16V1KX-GP"
			(at -2.8321 -1.7399 270)
			(unlocked yes)
			(layer "F.Fab")
			(hide yes)
			(effects
				(font
					(size 1.016 1.016)
					(thickness 0.1524)
				)
			)
		)
		(property "Device Type" "C0201H13"
			(at -2.8321 -3.2639 270)
			(unlocked yes)
			(layer "F.Fab")
			(hide yes)
			(effects
				(font
					(size 1.016 1.016)
					(thickness 0.1524)
				)
			)
		)
		(duplicate_pad_numbers_are_jumpers no)
		(fp_rect
			(start -0.2794 0.6477)
			(end 0.2794 -0.6477)
			(stroke
				(width 0)
				(type default)
			)
			(fill no)
			(layer "F.CrtYd")
		)
		(fp_rect
			(start -0.2794 0.6477)
			(end 0.2794 -0.6477)
			(stroke
				(width 0)
				(type default)
			)
			(fill no)
			(layer "F.Fab")
		)
		(pad "1" smd custom
			(at 0 -0.2794 270)
			(size 0.0762 0.0762)
			(layers "F.Cu" "F.Mask" "F.Paste")
			(net "PHY_IOC_TO_SCC_44_DP")
			(options
				(clearance outline)
				(anchor circle)
			)
			(primitives
				(gr_poly
					(pts
						(arc
							(start 0.1524 -0.127)
							(mid 0.137521 -0.162921)
							(end 0.1016 -0.1778)
						)
						(arc
							(start -0.1016 -0.1778)
							(mid -0.137521 -0.162921)
							(end -0.1524 -0.127)
						)
						(arc
							(start -0.1524 0.127)
							(mid -0.137521 0.162921)
							(end -0.1016 0.1778)
						)
						(arc
							(start 0.1016 0.1778)
							(mid 0.137521 0.162921)
							(end 0.1524 0.127)
						)
					)
					(width 0)
					(fill yes)
				)
			)
		)
		(pad "2" smd custom
			(at 0 0.2794 270)
			(size 0.0762 0.0762)
			(layers "F.Cu" "F.Mask" "F.Paste")
			(net "PHY_IOC_TO_SCC_C_44_DP")
			(options
				(clearance outline)
				(anchor circle)
			)
			(primitives
				(gr_poly
					(pts
						(arc
							(start 0.1524 -0.127)
							(mid 0.137521 -0.162921)
							(end 0.1016 -0.1778)
						)
						(arc
							(start -0.1016 -0.1778)
							(mid -0.137521 -0.162921)
							(end -0.1524 -0.127)
						)
						(arc
							(start -0.1524 0.127)
							(mid -0.137521 0.162921)
							(end -0.1016 0.1778)
						)
						(arc
							(start 0.1016 0.1778)
							(mid 0.137521 0.162921)
							(end 0.1524 0.127)
						)
					)
					(width 0)
					(fill yes)
				)
			)
		)
	)
	(footprint ""
		(layer "F.Cu")
		(at 94.216728 -81.788 180)
		(property "Reference" "R133"
			(at 0 0 180)
			(layer "F.SilkS")
			(hide yes)
			(effects
				(font
					(size 1.27 1.27)
				)
			)
		)
		(property "Value" "0R2J-2-GP"
			(at 0.064008 -3.993896 180)
			(unlocked yes)
			(layer "F.Fab")
			(hide yes)
			(effects
				(font
					(size 1.016 1.016)
					(thickness 0.1524)
				)
			)
		)
		(property "Device Type" "R402H16"
			(at 0.064008 -5.517896 180)
			(unlocked yes)
			(layer "F.Fab")
			(hide yes)
			(effects
				(font
					(size 1.016 1.016)
					(thickness 0.1524)
				)
			)
		)
		(duplicate_pad_numbers_are_jumpers no)
		(fp_line
			(start 0.508 -0.9398)
			(end -0.508 -0.9398)
			(stroke
				(width 0.1524)
				(type default)
			)
			(layer "F.SilkS")
		)
		(fp_line
			(start -0.508 -0.9398)
			(end -0.508 0.9398)
			(stroke
				(width 0.1524)
				(type default)
			)
			(layer "F.SilkS")
		)
		(fp_rect
			(start -0.508 0.9398)
			(end 0.508 -0.9398)
			(stroke
				(width 0)
				(type default)
			)
			(fill no)
			(layer "F.CrtYd")
		)
		(fp_rect
			(start -0.508 0.9398)
			(end 0.508 -0.9398)
			(stroke
				(width 0)
				(type default)
			)
			(fill no)
			(layer "F.Fab")
		)
		(pad "1" smd custom
			(at 0 -0.4445 180)
			(size 0.1397 0.1397)
			(layers "F.Cu" "F.Mask" "F.Paste")
			(net "SCC_RESET_LS_R_N")
			(options
				(clearance outline)
				(anchor circle)
			)
			(primitives
				(gr_poly
					(pts
						(arc
							(start -0.1778 -0.2794)
							(mid -0.249642 -0.249642)
							(end -0.2794 -0.1778)
						)
						(arc
							(start -0.2794 0.1778)
							(mid -0.249642 0.249642)
							(end -0.1778 0.2794)
						)
						(arc
							(start 0.1778 0.2794)
							(mid 0.249642 0.249642)
							(end 0.2794 0.1778)
						)
						(arc
							(start 0.2794 -0.1778)
							(mid 0.249642 -0.249642)
							(end 0.1778 -0.2794)
						)
					)
					(width 0)
					(fill yes)
				)
			)
		)
		(pad "2" smd custom
			(at 0 0.4445 180)
			(size 0.1397 0.1397)
			(layers "F.Cu" "F.Mask" "F.Paste")
			(net "SCC_RESET_LS_N")
			(options
				(clearance outline)
				(anchor circle)
			)
			(primitives
				(gr_poly
					(pts
						(arc
							(start -0.1778 -0.2794)
							(mid -0.249642 -0.249642)
							(end -0.2794 -0.1778)
						)
						(arc
							(start -0.2794 0.1778)
							(mid -0.249642 0.249642)
							(end -0.1778 0.2794)
						)
						(arc
							(start 0.1778 0.2794)
							(mid 0.249642 0.249642)
							(end 0.2794 0.1778)
						)
						(arc
							(start 0.2794 -0.1778)
							(mid 0.249642 -0.249642)
							(end 0.1778 -0.2794)
						)
					)
					(width 0)
					(fill yes)
				)
			)
		)
	)
	(footprint ""
		(layer "F.Cu")
		(at 22.1742 -49.5046 -90)
		(property "Reference" "R18"
			(at 0 0 270)
			(layer "F.SilkS")
			(hide yes)
			(effects
				(font
					(size 1.27 1.27)
				)
			)
		)
		(property "Value" "100KR2J-4-GP"
			(at 0.064008 -3.993896 270)
			(unlocked yes)
			(layer "F.Fab")
			(hide yes)
			(effects
				(font
					(size 1.016 1.016)
					(thickness 0.1524)
				)
			)
		)
		(property "Device Type" "R402H15"
			(at 0.064008 -5.517896 270)
			(unlocked yes)
			(layer "F.Fab")
			(hide yes)
			(effects
				(font
					(size 1.016 1.016)
					(thickness 0.1524)
				)
			)
		)
		(duplicate_pad_numbers_are_jumpers no)
		(fp_line
			(start -0.508 -0.9398)
			(end -0.508 0.9398)
			(stroke
				(width 0.1524)
				(type default)
			)
			(layer "F.SilkS")
		)
		(fp_line
			(start 0.508 -0.9398)
			(end -0.508 -0.9398)
			(stroke
				(width 0.1524)
				(type default)
			)
			(layer "F.SilkS")
		)
		(fp_rect
			(start -0.508 0.9398)
			(end 0.508 -0.9398)
			(stroke
				(width 0)
				(type default)
			)
			(fill no)
			(layer "F.CrtYd")
		)
		(fp_rect
			(start -0.508 0.9398)
			(end 0.508 -0.9398)
			(stroke
				(width 0)
				(type default)
			)
			(fill no)
			(layer "F.Fab")
		)
		(pad "1" smd custom
			(at 0 -0.4445 270)
			(size 0.1397 0.1397)
			(layers "F.Cu" "F.Mask" "F.Paste")
			(net "MB0_VCAP_R")
			(options
				(clearance outline)
				(anchor circle)
			)
			(primitives
				(gr_poly
					(pts
						(arc
							(start -0.1778 -0.2794)
							(mid -0.249642 -0.249642)
							(end -0.2794 -0.1778)
						)
						(arc
							(start -0.2794 0.1778)
							(mid -0.249642 0.249642)
							(end -0.1778 0.2794)
						)
						(arc
							(start 0.1778 0.2794)
							(mid 0.249642 0.249642)
							(end 0.2794 0.1778)
						)
						(arc
							(start 0.2794 -0.1778)
							(mid 0.249642 -0.249642)
							(end 0.1778 -0.2794)
						)
					)
					(width 0)
					(fill yes)
				)
			)
		)
		(pad "2" smd custom
			(at 0 0.4445 270)
			(size 0.1397 0.1397)
			(layers "F.Cu" "F.Mask" "F.Paste")
			(net "MB0_PSET_R")
			(options
				(clearance outline)
				(anchor circle)
			)
			(primitives
				(gr_poly
					(pts
						(arc
							(start -0.1778 -0.2794)
							(mid -0.249642 -0.249642)
							(end -0.2794 -0.1778)
						)
						(arc
							(start -0.2794 0.1778)
							(mid -0.249642 0.249642)
							(end -0.1778 0.2794)
						)
						(arc
							(start 0.1778 0.2794)
							(mid 0.249642 0.249642)
							(end 0.2794 0.1778)
						)
						(arc
							(start 0.2794 -0.1778)
							(mid 0.249642 -0.249642)
							(end 0.1778 -0.2794)
						)
					)
					(width 0)
					(fill yes)
				)
			)
		)
	)
	(footprint ""
		(layer "F.Cu")
		(at 158.69158 -116.39042)
		(property "Reference" "C606"
			(at 0 0 0)
			(layer "F.SilkS")
			(hide yes)
			(effects
				(font
					(size 1.27 1.27)
				)
			)
		)
		(property "Value" "SC1U16V3KX-5GP"
			(at 0 -2.8194 0)
			(unlocked yes)
			(layer "F.Fab")
			(hide yes)
			(effects
				(font
					(size 1.016 1.016)
					(thickness 0.1524)
				)
			)
		)
		(property "Device Type" "C603H36"
			(at 0 -4.3434 0)
			(unlocked yes)
			(layer "F.Fab")
			(hide yes)
			(effects
				(font
					(size 1.016 1.016)
					(thickness 0.1524)
				)
			)
		)
		(duplicate_pad_numbers_are_jumpers no)
		(fp_line
			(start 0.508 0)
			(end -0.508 0)
			(stroke
				(width 0.2032)
				(type default)
			)
			(layer "F.SilkS")
		)
		(fp_rect
			(start -0.5842 1.3335)
			(end 0.5842 -1.3335)
			(stroke
				(width 0)
				(type default)
			)
			(fill no)
			(layer "F.CrtYd")
		)
		(fp_rect
			(start -0.5842 1.3335)
			(end 0.5842 -1.3335)
			(stroke
				(width 0)
				(type default)
			)
			(fill no)
			(layer "F.Fab")
		)
		(pad "1" smd custom
			(at 0 -0.762)
			(size 0.2159 0.2159)
			(layers "F.Cu" "F.Mask" "F.Paste")
			(net "GND")
			(options
				(clearance outline)
				(anchor circle)
			)
			(primitives
				(gr_poly
					(pts
						(arc
							(start -0.3302 -0.4318)
							(mid -0.402042 -0.402042)
							(end -0.4318 -0.3302)
						)
						(arc
							(start -0.4318 0.3302)
							(mid -0.402042 0.402042)
							(end -0.3302 0.4318)
						)
						(arc
							(start 0.3302 0.4318)
							(mid 0.402042 0.402042)
							(end 0.4318 0.3302)
						)
						(arc
							(start 0.4318 -0.3302)
							(mid 0.402042 -0.402042)
							(end 0.3302 -0.4318)
						)
					)
					(width 0)
					(fill yes)
				)
			)
		)
		(pad "2" smd custom
			(at 0 0.762)
			(size 0.2159 0.2159)
			(layers "F.Cu" "F.Mask" "F.Paste")
			(net "P1V5_E_VREG")
			(options
				(clearance outline)
				(anchor circle)
			)
			(primitives
				(gr_poly
					(pts
						(arc
							(start -0.3302 -0.4318)
							(mid -0.402042 -0.402042)
							(end -0.4318 -0.3302)
						)
						(arc
							(start -0.4318 0.3302)
							(mid -0.402042 0.402042)
							(end -0.3302 0.4318)
						)
						(arc
							(start 0.3302 0.4318)
							(mid 0.402042 0.402042)
							(end 0.4318 0.3302)
						)
						(arc
							(start 0.4318 -0.3302)
							(mid 0.402042 -0.402042)
							(end 0.3302 -0.4318)
						)
					)
					(width 0)
					(fill yes)
				)
			)
		)
	)
	(footprint ""
		(layer "F.Cu")
		(at 70.104 -8.509 90)
		(property "Reference" "R105"
			(at 0 0 90)
			(layer "F.SilkS")
			(hide yes)
			(effects
				(font
					(size 1.27 1.27)
				)
			)
		)
		(property "Value" "0R2J-2-GP"
			(at 0.064008 -3.993896 90)
			(unlocked yes)
			(layer "F.Fab")
			(hide yes)
			(effects
				(font
					(size 1.016 1.016)
					(thickness 0.1524)
				)
			)
		)
		(property "Device Type" "R402H16"
			(at 0.064008 -5.517896 90)
			(unlocked yes)
			(layer "F.Fab")
			(hide yes)
			(effects
				(font
					(size 1.016 1.016)
					(thickness 0.1524)
				)
			)
		)
		(duplicate_pad_numbers_are_jumpers no)
		(fp_line
			(start 0.508 -0.9398)
			(end -0.508 -0.9398)
			(stroke
				(width 0.1524)
				(type default)
			)
			(layer "F.SilkS")
		)
		(fp_line
			(start -0.508 -0.9398)
			(end -0.508 0.9398)
			(stroke
				(width 0.1524)
				(type default)
			)
			(layer "F.SilkS")
		)
		(fp_rect
			(start -0.508 0.9398)
			(end 0.508 -0.9398)
			(stroke
				(width 0)
				(type default)
			)
			(fill no)
			(layer "F.CrtYd")
		)
		(fp_rect
			(start -0.508 0.9398)
			(end 0.508 -0.9398)
			(stroke
				(width 0)
				(type default)
			)
			(fill no)
			(layer "F.Fab")
		)
		(pad "1" smd custom
			(at 0 -0.4445 90)
			(size 0.1397 0.1397)
			(layers "F.Cu" "F.Mask" "F.Paste")
			(net "GND")
			(options
				(clearance outline)
				(anchor circle)
			)
			(primitives
				(gr_poly
					(pts
						(arc
							(start -0.1778 -0.2794)
							(mid -0.249642 -0.249642)
							(end -0.2794 -0.1778)
						)
						(arc
							(start -0.2794 0.1778)
							(mid -0.249642 0.249642)
							(end -0.1778 0.2794)
						)
						(arc
							(start 0.1778 0.2794)
							(mid 0.249642 0.249642)
							(end 0.2794 0.1778)
						)
						(arc
							(start 0.2794 -0.1778)
							(mid 0.249642 -0.249642)
							(end 0.1778 -0.2794)
						)
					)
					(width 0)
					(fill yes)
				)
			)
		)
		(pad "2" smd custom
			(at 0 0.4445 90)
			(size 0.1397 0.1397)
			(layers "F.Cu" "F.Mask" "F.Paste")
			(net "SCC_TYPE_2")
			(options
				(clearance outline)
				(anchor circle)
			)
			(primitives
				(gr_poly
					(pts
						(arc
							(start -0.1778 -0.2794)
							(mid -0.249642 -0.249642)
							(end -0.2794 -0.1778)
						)
						(arc
							(start -0.2794 0.1778)
							(mid -0.249642 0.249642)
							(end -0.1778 0.2794)
						)
						(arc
							(start 0.1778 0.2794)
							(mid 0.249642 0.249642)
							(end 0.2794 0.1778)
						)
						(arc
							(start 0.2794 -0.1778)
							(mid 0.249642 -0.249642)
							(end 0.1778 -0.2794)
						)
					)
					(width 0)
					(fill yes)
				)
			)
		)
	)
	(footprint ""
		(layer "F.Cu")
		(at 62.7761 -60.6044 -90)
		(property "Reference" "TC2"
			(at 0 0 270)
			(layer "F.SilkS")
			(hide yes)
			(effects
				(font
					(size 1.27 1.27)
				)
			)
		)
		(property "Value" "SE470UF2VDM-GP"
			(at 0 -9.6012 270)
			(unlocked yes)
			(layer "F.Fab")
			(hide yes)
			(effects
				(font
					(size 1.016 1.016)
					(thickness 0.1524)
				)
			)
		)
		(property "Device Type" "CT7343H83"
			(at 0 -11.1252 270)
			(unlocked yes)
			(layer "F.Fab")
			(hide yes)
			(effects
				(font
					(size 1.016 1.016)
					(thickness 0.1524)
				)
			)
		)
		(duplicate_pad_numbers_are_jumpers no)
		(fp_line
			(start -2.286 4.8768)
			(end -2.286 2.032)
			(stroke
				(width 0.1524)
				(type default)
			)
			(layer "F.SilkS")
		)
		(fp_line
			(start 2.286 4.8768)
			(end -2.286 4.8768)
			(stroke
				(width 0.1524)
				(type default)
			)
			(layer "F.SilkS")
		)
		(fp_line
			(start 2.286 2.032)
			(end 2.286 4.8768)
			(stroke
				(width 0.1524)
				(type default)
			)
			(layer "F.SilkS")
		)
		(fp_line
			(start 2.286 -2.032)
			(end 2.286 -4.8768)
			(stroke
				(width 0.1524)
				(type default)
			)
			(layer "F.SilkS")
		)
		(fp_line
			(start 2.1082 -4.699)
			(end -2.1082 -4.699)
			(stroke
				(width 0.508)
				(type default)
			)
			(layer "F.SilkS")
		)
		(fp_line
			(start -2.286 -4.8768)
			(end -2.286 -2.032)
			(stroke
				(width 0.1524)
				(type default)
			)
			(layer "F.SilkS")
		)
		(fp_line
			(start 2.286 -4.8768)
			(end -2.286 -4.8768)
			(stroke
				(width 0.1524)
				(type default)
			)
			(layer "F.SilkS")
		)
		(fp_rect
			(start -2.1463 3.6449)
			(end 2.1463 -3.6449)
			(stroke
				(width 0)
				(type default)
			)
			(fill no)
			(layer "F.CrtYd")
		)
		(fp_poly
			(pts
				(xy -2.54 4.953) (xy -2.54 4.2926) (xy -3.81 4.2926) (xy -3.81 -4.2926) (xy -2.54 -4.2926) (xy -2.54 -4.953)
				(xy 2.54 -4.953) (xy 2.54 -4.2926) (xy 3.81 -4.2926) (xy 3.81 -1.6256) (xy 2.1463 -1.6256) (xy 2.1463 -3.6449)
				(xy -2.1463 -3.6449) (xy -2.1463 3.6449) (xy 2.1463 3.6449) (xy 2.1463 -1.6129) (xy 3.81 -1.6129)
				(xy 3.81 4.2926) (xy 2.54 4.2926) (xy 2.54 4.953)
			)
			(stroke
				(width 0)
				(type default)
			)
			(fill no)
			(layer "F.CrtYd")
		)
		(fp_rect
			(start -2.54 4.953)
			(end 2.54 -4.953)
			(stroke
				(width 0)
				(type default)
			)
			(fill no)
			(layer "F.Fab")
		)
		(fp_rect
			(start -3.81 4.2926)
			(end -2.54 -4.2926)
			(stroke
				(width 0)
				(type default)
			)
			(fill no)
			(layer "F.Fab")
		)
		(fp_rect
			(start 2.54 4.2926)
			(end 3.81 -4.2926)
			(stroke
				(width 0)
				(type default)
			)
			(fill no)
			(layer "F.Fab")
		)
		(pad "1" smd rect
			(at 0 -3.1496 270)
			(size 2.413 2.286)
			(layers "F.Cu" "F.Mask" "F.Paste")
			(net "P0V9")
		)
		(pad "2" smd rect
			(at 0 3.1496 270)
			(size 2.413 2.286)
			(layers "F.Cu" "F.Mask" "F.Paste")
			(net "GND")
		)
		(zone
			(layer "F.Cu")
			(hatch none 0.5)
			(connect_pads
				(clearance 0)
			)
			(min_thickness 0.25)
			(keepout
				(tracks allowed)
				(vias not_allowed)
				(pads allowed)
				(copperpour not_allowed)
				(footprints allowed)
			)
			(placement
				(enabled no)
				(sheetname "")
			)
			(fill
				(thermal_gap 0.5)
				(thermal_bridge_width 0.5)
				(island_removal_mode 0)
			)
			(polygon
				(pts
					(xy 58.1787 -62.1157) (xy 58.1787 -59.0931) (xy 61.0743 -59.0931) (xy 61.4045 -59.0931) (xy 61.4045 -62.1157)
					(xy 61.0743 -62.1157)
				)
			)
		)
		(zone
			(layer "F.Cu")
			(hatch none 0.5)
			(connect_pads
				(clearance 0)
			)
			(min_thickness 0.25)
			(keepout
				(tracks allowed)
				(vias not_allowed)
				(pads allowed)
				(copperpour not_allowed)
				(footprints allowed)
			)
			(placement
				(enabled no)
				(sheetname "")
			)
			(fill
				(thermal_gap 0.5)
				(thermal_bridge_width 0.5)
				(island_removal_mode 0)
			)
			(polygon
				(pts
					(xy 64.4652 -59.0931) (xy 67.3735 -59.0931) (xy 67.3735 -62.1157) (xy 64.4779 -62.1157) (xy 64.1477 -62.1157)
					(xy 64.1477 -59.0931)
				)
			)
		)
	)
	(footprint ""
		(layer "F.Cu")
		(at 196.528944 -74.46772 90)
		(property "Reference" "R296"
			(at 0 0 90)
			(layer "F.SilkS")
			(hide yes)
			(effects
				(font
					(size 1.27 1.27)
				)
			)
		)
		(property "Value" "0R2J-2-GP"
			(at 0.064008 -3.993896 90)
			(unlocked yes)
			(layer "F.Fab")
			(hide yes)
			(effects
				(font
					(size 1.016 1.016)
					(thickness 0.1524)
				)
			)
		)
		(property "Device Type" "R402H16"
			(at 0.064008 -5.517896 90)
			(unlocked yes)
			(layer "F.Fab")
			(hide yes)
			(effects
				(font
					(size 1.016 1.016)
					(thickness 0.1524)
				)
			)
		)
		(duplicate_pad_numbers_are_jumpers no)
		(fp_line
			(start 0.508 -0.9398)
			(end -0.508 -0.9398)
			(stroke
				(width 0.1524)
				(type default)
			)
			(layer "F.SilkS")
		)
		(fp_line
			(start -0.508 -0.9398)
			(end -0.508 0.9398)
			(stroke
				(width 0.1524)
				(type default)
			)
			(layer "F.SilkS")
		)
		(fp_rect
			(start -0.508 0.9398)
			(end 0.508 -0.9398)
			(stroke
				(width 0)
				(type default)
			)
			(fill no)
			(layer "F.CrtYd")
		)
		(fp_rect
			(start -0.508 0.9398)
			(end 0.508 -0.9398)
			(stroke
				(width 0)
				(type default)
			)
			(fill no)
			(layer "F.Fab")
		)
		(pad "1" smd custom
			(at 0 -0.4445 90)
			(size 0.1397 0.1397)
			(layers "F.Cu" "F.Mask" "F.Paste")
			(net "IOC_UART_0_TX_R")
			(options
				(clearance outline)
				(anchor circle)
			)
			(primitives
				(gr_poly
					(pts
						(arc
							(start -0.1778 -0.2794)
							(mid -0.249642 -0.249642)
							(end -0.2794 -0.1778)
						)
						(arc
							(start -0.2794 0.1778)
							(mid -0.249642 0.249642)
							(end -0.1778 0.2794)
						)
						(arc
							(start 0.1778 0.2794)
							(mid 0.249642 0.249642)
							(end 0.2794 0.1778)
						)
						(arc
							(start 0.2794 -0.1778)
							(mid 0.249642 -0.249642)
							(end 0.1778 -0.2794)
						)
					)
					(width 0)
					(fill yes)
				)
			)
		)
		(pad "2" smd custom
			(at 0 0.4445 90)
			(size 0.1397 0.1397)
			(layers "F.Cu" "F.Mask" "F.Paste")
			(net "IOC_UART_0_TX")
			(options
				(clearance outline)
				(anchor circle)
			)
			(primitives
				(gr_poly
					(pts
						(arc
							(start -0.1778 -0.2794)
							(mid -0.249642 -0.249642)
							(end -0.2794 -0.1778)
						)
						(arc
							(start -0.2794 0.1778)
							(mid -0.249642 0.249642)
							(end -0.1778 0.2794)
						)
						(arc
							(start 0.1778 0.2794)
							(mid 0.249642 0.249642)
							(end 0.2794 0.1778)
						)
						(arc
							(start 0.2794 -0.1778)
							(mid 0.249642 -0.249642)
							(end 0.1778 -0.2794)
						)
					)
					(width 0)
					(fill yes)
				)
			)
		)
	)
)
